FILE_TYPE = CONNECTIVITY;
{Allegro Design Entry HDL 16.6-p007 (v16-6-112F) 10/10/2012}
"PAGE_NUMBER" = 84;
0"NC";
1"M_K_DQS_DN<17:0>";
2"M_K_DQS_DP<17:0>";
3"M_K_DQ<63:0>";
4"M_K_MA<17:0>";
5"M_K_CLK_DP<3:0>";
6"M_K_BG<1:0>";
7"M_K_BA<1:0>";
8"M_K_ECC<7:0>";
9"M_K_CS_N<7:0>";
10"M_K_CKE<3:0>";
11"M_K_ODT<3:0>";
12"M_K_CLK_DN<3:0>";
13"GND\g";
14"PVTT_KLM\g";
15"PVPP_KLM\g";
16"GND\g";
17"GND\g";
18"P12V_NVDIMM_KLM\g";
19"GND\g";
20"PVPP_KLM\g";
21"PVDDQ_KLM\g";
22"M_K_DQ<60>";
23"M_K_DQS_DN<7>";
24"M_K_DQS_DN<6>";
25"M_K_DQS_DP<7>";
26"M_K_DQS_DN<15>";
27"M_K_DQ<61>";
28"M_K_DQS_DP<4>";
29"M_K_ALERT_N";
30"M_K_DQ<31>";
31"M_K_DQ<32>";
32"M_K_DQ<63>";
33"M_K_DQS_DN<4>";
34"M_K_DQS_DP<3>";
35"M_K_DQS_DN<3>";
36"M_K_DQS_DN<2>";
37"M_K_DQS_DP<1>";
38"M_K_DQS_DN<1>";
39"M_K_DQS_DP<0>";
40"M_K_VREF";
41"TP_CH_K_DIMM0_RFU_2";
42"TP_CH_K_DIMM0_RFU_0";
43"TP_CH_K_DIMM0_RFU_1";
44"M_K_CLK_DN<3>";
45"M_K_CLK_DN<2>";
46"FM_ADR_COMPLETE_KLM_N";
47"SMB_DDR_KLM_VPP_SCL";
48"SMB_DDR_KLM_VPP_SDA";
49"M_K_ACT_N";
50"M_K_DQ<1>";
51"M_K_DQ<2>";
52"M_K_DQ<3>";
53"M_K_DQ<4>";
54"M_K_DQ<0>";
55"M_K_DQ<14>";
56"M_K_DQ<13>";
57"M_K_DQ<12>";
58"M_K_DQ<11>";
59"M_K_DQ<10>";
60"M_K_DQ<8>";
61"M_K_DQ<7>";
62"M_K_DQ<6>";
63"M_K_DQ<5>";
64"M_K_DQ<9>";
65"M_K_PAR";
66"M_KLM_RST_N";
67"M_K_CS_N<7>";
68"M_K_CS_N<6>";
69"M_K_CS_N<5>";
70"M_K_ECC<5>";
71"M_K_ECC<4>";
72"M_K_ECC<3>";
73"M_K_ECC<2>";
74"M_K_ECC<1>";
75"M_K_ECC<0>";
76"M_K_CKE<3>";
77"M_K_ECC<7>";
78"M_K_ODT<2>";
79"M_K_ODT<3>";
80"M_K_CKE<2>";
81"M_K_CS_N<4>";
82"M_K_ECC<6>";
83"M_K_C<2>";
84"M_K_BA<1>";
85"M_K_MA<0>";
86"M_K_MA<1>";
87"M_K_MA<3>";
88"M_K_MA<4>";
89"M_K_MA<5>";
90"M_K_MA<6>";
91"M_K_MA<7>";
92"M_K_MA<8>";
93"M_K_MA<9>";
94"M_K_BA<0>";
95"M_K_MA<2>";
96"M_K_BG<1>";
97"M_K_BG<0>";
98"M_K_CLK_DP<3>";
99"M_K_CLK_DP<2>";
100"M_K_DQ<24>";
101"M_K_DQ<23>";
102"M_K_DQ<22>";
103"M_K_DQ<21>";
104"M_K_DQ<20>";
105"M_K_DQ<19>";
106"M_K_DQ<18>";
107"M_K_DQ<16>";
108"M_K_DQ<15>";
109"M_K_DQ<17>";
110"M_K_DQ<29>";
111"M_K_DQ<28>";
112"M_K_DQ<34>";
113"M_K_DQ<33>";
114"M_K_DQ<30>";
115"M_K_DQ<25>";
116"M_K_DQ<27>";
117"M_K_DQ<26>";
118"M_K_DQ<45>";
119"M_K_DQ<44>";
120"M_K_DQ<43>";
121"M_K_DQ<42>";
122"M_K_DQ<39>";
123"M_K_DQ<37>";
124"M_K_DQ<36>";
125"M_K_DQ<38>";
126"M_K_DQ<35>";
127"M_K_DQ<40>";
128"M_K_DQ<41>";
129"M_K_DQ<55>";
130"M_K_DQ<46>";
131"M_K_DQ<54>";
132"M_K_DQ<53>";
133"M_K_DQ<52>";
134"M_K_DQ<51>";
135"M_K_DQ<50>";
136"M_K_DQ<49>";
137"M_K_DQ<48>";
138"M_K_DQ<47>";
139"M_K_MA<12>";
140"M_K_MA<17>";
141"M_K_MA<10>";
142"M_K_MA<11>";
143"M_K_MA<14>";
144"M_K_MA<15>";
145"M_K_MA<16>";
146"M_K_MA<13>";
147"M_K_DQ<59>";
148"M_K_DQ<56>";
149"M_K_DQ<57>";
150"M_K_DQ<58>";
151"M_K_DQ<62>";
152"M_K_DQS_DP<2>";
153"M_K_DQS_DN<0>";
154"M_K_DQS_DN<5>";
155"M_K_DQS_DP<5>";
156"M_K_DQS_DP<6>";
157"M_K_DQS_DP<8>";
158"M_K_DQS_DP<9>";
159"M_K_DQS_DN<10>";
160"M_K_DQS_DN<8>";
161"M_K_DQS_DN<9>";
162"M_K_DQS_DP<10>";
163"M_K_DQS_DP<11>";
164"M_K_DQS_DP<12>";
165"M_K_DQS_DP<13>";
166"M_K_DQS_DP<14>";
167"M_K_DQS_DN<11>";
168"M_K_DQS_DN<12>";
169"M_K_DQS_DN<13>";
170"M_K_DQS_DN<14>";
171"M_K_DQS_DP<15>";
172"M_K_DQS_DP<16>";
173"M_K_DQS_DP<17>";
174"M_K_DQS_DN<16>";
175"M_K_DQS_DN<17>";
176"FM_DIMM_EVENT_COD_N";
%"GND"
"1","(-3500,1475)","2","mstr_symbols","I1";
;
VOLTAGE"0"
SIZE"1B"
CDS_LIB"mstr_symbols"
BOM_COST"MEM"
BODY_TYPE"PLUMBING"
ROOM"DDR4_CH_C"
HDL_POWER"GND";
"A\NAC"13;
%"PVTT_KLM"
"1","(600,2425)","0","mstr_symbols","I100";
;
VOLTAGE"0.6V"
BOM_COST"MEM"
CDS_LIB"mstr_symbols"
BODY_TYPE"PLUMBING"
ROOM"DDR4_CH_C"
HDL_POWER"PVTT_KLM";
"G\NAC"14;
%"PVPP_KLM"
"1","(750,2725)","0","mstr_symbols","I101";
;
VOLTAGE"2.5V"
BOM_COST"MEM"
CDS_LIB"mstr_symbols"
BODY_TYPE"PLUMBING"
ROOM"DDR4_CH_C"
HDL_POWER"PVPP_KLM";
"G\NAC"15;
%"SCONN288_H44441003"
"2","(1600,3975)","0","mstr_sconn","I102";
;
CDS_SEC"2"
PART_NUMBER"H44441-003"
MATERIAL"SCONN"
LOCATION"J9M1"
BOM_SS"NOPOP"
PACK_TYPE"PIP"
BOM_COST"MEM"
CDS_LIB"mstr_sconn"
SEC_TYPE"PIP"
SEC"2"
CDS_LOCATION"J9M1"
ROOM"DDR4_CH_K";
"DQS0N"
$PN"152"153;
"DQS0P"
$PN"153"39;
"DQS10N"
$PN"19"159;
"DQS10P"
$PN"18"162;
"DQS11N"
$PN"30"167;
"DQS11P"
$PN"29"163;
"DQS12N"
$PN"41"168;
"DQS12P"
$PN"40"164;
"DQS13N"
$PN"100"169;
"DQS13P"
$PN"99"165;
"DQS14N"
$PN"111"170;
"DQS14P"
$PN"110"166;
"DQS15N"
$PN"122"26;
"DQS15P"
$PN"121"171;
"DQS16N"
$PN"133"174;
"DQS16P"
$PN"132"172;
"DQS17N"
$PN"52"175;
"DQS17P"
$PN"51"173;
"DQS1N"
$PN"163"38;
"DQS1P"
$PN"164"37;
"DQS2N"
$PN"174"36;
"DQS2P"
$PN"175"152;
"DQS3N"
$PN"185"35;
"DQS3P"
$PN"186"34;
"DQS4N"
$PN"244"33;
"DQS4P"
$PN"245"28;
"DQS5N"
$PN"255"154;
"DQS5P"
$PN"256"155;
"DQS6N"
$PN"266"24;
"DQS6P"
$PN"267"156;
"DQS7N"
$PN"277"23;
"DQS7P"
$PN"278"25;
"DQS8N"
$PN"196"160;
"DQS8P"
$PN"197"157;
"DQS9N"
$PN"8"161;
"DQS9P"
$PN"7"158;
%"TAP"
"6","(-1600,3775)","0","mstr_standard","I104";
;
CDS_LIB"mstr_standard"
BODY_TYPE"PLUMBING"
HDL_TAP"TRUE";
"B \NAC \NWC"4;
"S \NAC"
BN"3"87;
%"TAP"
"6","(-1600,3725)","0","mstr_standard","I105";
;
CDS_LIB"mstr_standard"
BODY_TYPE"PLUMBING"
HDL_TAP"TRUE";
"B \NAC \NWC"4;
"S \NAC"
BN"2"95;
%"TAP"
"6","(-1600,3925)","0","mstr_standard","I106";
;
CDS_LIB"mstr_standard"
BODY_TYPE"PLUMBING"
HDL_TAP"TRUE";
"B \NAC \NWC"4;
"S \NAC"
BN"6"90;
%"TAP"
"6","(-1600,3875)","0","mstr_standard","I107";
;
CDS_LIB"mstr_standard"
BODY_TYPE"PLUMBING"
HDL_TAP"TRUE";
"B \NAC \NWC"4;
"S \NAC"
BN"5"89;
%"TAP"
"6","(-1600,3825)","0","mstr_standard","I108";
;
CDS_LIB"mstr_standard"
BODY_TYPE"PLUMBING"
HDL_TAP"TRUE";
"B \NAC \NWC"4;
"S \NAC"
BN"4"88;
%"TAP"
"6","(-1600,3975)","0","mstr_standard","I109";
;
CDS_LIB"mstr_standard"
BODY_TYPE"PLUMBING"
HDL_TAP"TRUE";
"B \NAC \NWC"4;
"S \NAC"
BN"7"91;
%"TAP"
"6","(-1600,4025)","0","mstr_standard","I110";
;
CDS_LIB"mstr_standard"
BODY_TYPE"PLUMBING"
HDL_TAP"TRUE";
"B \NAC \NWC"4;
"S \NAC"
BN"8"92;
%"TAP"
"6","(-1600,4075)","0","mstr_standard","I111";
;
CDS_LIB"mstr_standard"
BODY_TYPE"PLUMBING"
HDL_TAP"TRUE";
"B \NAC \NWC"4;
"S \NAC"
BN"9"93;
%"TAP"
"6","(-1600,4175)","0","mstr_standard","I112";
;
CDS_LIB"mstr_standard"
BODY_TYPE"PLUMBING"
HDL_TAP"TRUE";
"B \NAC \NWC"4;
"S \NAC"
BN"11"142;
%"TAP"
"6","(-1600,4125)","0","mstr_standard","I113";
;
CDS_LIB"mstr_standard"
BODY_TYPE"PLUMBING"
HDL_TAP"TRUE";
"B \NAC \NWC"4;
"S \NAC"
BN"10"141;
%"TAP"
"6","(-1600,4225)","0","mstr_standard","I114";
;
CDS_LIB"mstr_standard"
BODY_TYPE"PLUMBING"
HDL_TAP"TRUE";
"B \NAC \NWC"4;
"S \NAC"
BN"12"139;
%"TAP"
"6","(-1600,4275)","0","mstr_standard","I115";
;
CDS_LIB"mstr_standard"
BODY_TYPE"PLUMBING"
HDL_TAP"TRUE";
"B \NAC \NWC"4;
"S \NAC"
BN"13"146;
%"TAP"
"6","(-1600,4325)","0","mstr_standard","I116";
;
CDS_LIB"mstr_standard"
BODY_TYPE"PLUMBING"
HDL_TAP"TRUE";
"B \NAC \NWC"4;
"S \NAC"
BN"14"143;
%"TAP"
"6","(-1600,4425)","0","mstr_standard","I117";
;
CDS_LIB"mstr_standard"
BODY_TYPE"PLUMBING"
HDL_TAP"TRUE";
"B \NAC \NWC"4;
"S \NAC"
BN"16"145;
%"TAP"
"6","(-1600,4375)","0","mstr_standard","I118";
;
CDS_LIB"mstr_standard"
BODY_TYPE"PLUMBING"
HDL_TAP"TRUE";
"B \NAC \NWC"4;
"S \NAC"
BN"15"144;
%"TAP"
"6","(-1600,4475)","0","mstr_standard","I119";
;
CDS_LIB"mstr_standard"
BODY_TYPE"PLUMBING"
HDL_TAP"TRUE";
"B \NAC \NWC"4;
"S \NAC"
BN"17"140;
%"TAP"
"6","(-100,3825)","2","mstr_standard","I120";
;
CDS_LIB"mstr_standard"
BODY_TYPE"PLUMBING"
HDL_TAP"TRUE";
"B \NAC \NWC"3;
"S \NAC"
BN"50"135;
%"TAP"
"6","(-100,3725)","2","mstr_standard","I121";
;
CDS_LIB"mstr_standard"
BODY_TYPE"PLUMBING"
HDL_TAP"TRUE";
"B \NAC \NWC"3;
"S \NAC"
BN"48"137;
%"TAP"
"6","(-100,3775)","2","mstr_standard","I122";
;
CDS_LIB"mstr_standard"
BODY_TYPE"PLUMBING"
HDL_TAP"TRUE";
"B \NAC \NWC"3;
"S \NAC"
BN"49"136;
%"TAP"
"6","(-100,3975)","2","mstr_standard","I123";
;
CDS_LIB"mstr_standard"
BODY_TYPE"PLUMBING"
HDL_TAP"TRUE";
"B \NAC \NWC"3;
"S \NAC"
BN"53"132;
%"TAP"
"6","(-100,3925)","2","mstr_standard","I124";
;
CDS_LIB"mstr_standard"
BODY_TYPE"PLUMBING"
HDL_TAP"TRUE";
"B \NAC \NWC"3;
"S \NAC"
BN"52"133;
%"TAP"
"6","(-100,3875)","2","mstr_standard","I125";
;
CDS_LIB"mstr_standard"
BODY_TYPE"PLUMBING"
HDL_TAP"TRUE";
"B \NAC \NWC"3;
"S \NAC"
BN"51"134;
%"TAP"
"6","(-100,4075)","2","mstr_standard","I126";
;
CDS_LIB"mstr_standard"
BODY_TYPE"PLUMBING"
HDL_TAP"TRUE";
"B \NAC \NWC"3;
"S \NAC"
BN"55"129;
%"TAP"
"6","(-100,4025)","2","mstr_standard","I127";
;
CDS_LIB"mstr_standard"
BODY_TYPE"PLUMBING"
HDL_TAP"TRUE";
"B \NAC \NWC"3;
"S \NAC"
BN"54"131;
%"TAP"
"6","(-100,4175)","2","mstr_standard","I128";
;
CDS_LIB"mstr_standard"
BODY_TYPE"PLUMBING"
HDL_TAP"TRUE";
"B \NAC \NWC"3;
"S \NAC"
BN"57"149;
%"TAP"
"6","(-100,4225)","2","mstr_standard","I129";
;
CDS_LIB"mstr_standard"
BODY_TYPE"PLUMBING"
HDL_TAP"TRUE";
"B \NAC \NWC"3;
"S \NAC"
BN"58"150;
%"TAP"
"6","(-100,4125)","2","mstr_standard","I130";
;
CDS_LIB"mstr_standard"
BODY_TYPE"PLUMBING"
HDL_TAP"TRUE";
"B \NAC \NWC"3;
"S \NAC"
BN"56"148;
%"TAP"
"6","(-100,4275)","2","mstr_standard","I131";
;
CDS_LIB"mstr_standard"
BODY_TYPE"PLUMBING"
HDL_TAP"TRUE";
"B \NAC \NWC"3;
"S \NAC"
BN"59"147;
%"TAP"
"6","(-100,4325)","2","mstr_standard","I132";
;
CDS_LIB"mstr_standard"
BODY_TYPE"PLUMBING"
HDL_TAP"TRUE";
"B \NAC \NWC"3;
"S \NAC"
BN"60"22;
%"TAP"
"6","(-100,4475)","2","mstr_standard","I133";
;
CDS_LIB"mstr_standard"
BODY_TYPE"PLUMBING"
HDL_TAP"TRUE";
"B \NAC \NWC"3;
"S \NAC"
BN"63"32;
%"TAP"
"6","(-100,4425)","2","mstr_standard","I134";
;
CDS_LIB"mstr_standard"
BODY_TYPE"PLUMBING"
HDL_TAP"TRUE";
"B \NAC \NWC"3;
"S \NAC"
BN"62"151;
%"TAP"
"6","(-100,4375)","2","mstr_standard","I135";
;
CDS_LIB"mstr_standard"
BODY_TYPE"PLUMBING"
HDL_TAP"TRUE";
"B \NAC \NWC"3;
"S \NAC"
BN"61"27;
%"GND"
"1","(2700,725)","2","mstr_symbols","I137";
;
VOLTAGE"0"
CDS_LIB"mstr_symbols"
SIZE"1B"
BOM_COST"MEM"
BODY_TYPE"PLUMBING"
ROOM"DDR4_CH_C"
HDL_POWER"GND";
"A\NAC"16;
%"SCONN288_H44441003"
"3","(3400,2025)","0","mstr_sconn","I138";
;
CDS_SEC"3"
LOCATION"J9M1"
PART_NUMBER"H44441-003"
MATERIAL"SCONN"
BOM_SS"NOPOP"
PACK_TYPE"PIP"
BOM_COST"MEM"
CDS_LIB"mstr_sconn"
SEC_TYPE"PIP"
SEC"3"
CDS_LOCATION"J9M1"
ROOM"DDR4_CH_K";
"VSS<46>"
$PN"147"17;
"VSS<45>"
$PN"149"17;
"VSS<87>"
$PN"15"16;
"VSS<86>"
$PN"17"16;
"VSS<85>"
$PN"20"16;
"VSS<84>"
$PN"22"16;
"VSS<83>"
$PN"24"16;
"VSS<82>"
$PN"26"16;
"VSS<81>"
$PN"28"16;
"VSS<80>"
$PN"31"16;
"VSS<79>"
$PN"33"16;
"VSS<78>"
$PN"35"16;
"VSS<77>"
$PN"37"16;
"VSS<76>"
$PN"39"16;
"VSS<75>"
$PN"42"16;
"VSS<74>"
$PN"44"16;
"VSS<73>"
$PN"46"16;
"VSS<72>"
$PN"48"16;
"VSS<71>"
$PN"50"16;
"VSS<70>"
$PN"53"16;
"VSS<69>"
$PN"55"16;
"VSS<68>"
$PN"57"16;
"VSS<67>"
$PN"94"16;
"VSS<66>"
$PN"96"16;
"VSS<65>"
$PN"98"16;
"VSS<64>"
$PN"101"16;
"VSS<63>"
$PN"103"16;
"VSS<62>"
$PN"105"16;
"VSS<61>"
$PN"107"16;
"VSS<60>"
$PN"109"16;
"VSS<59>"
$PN"112"16;
"VSS<58>"
$PN"114"16;
"VSS<57>"
$PN"116"16;
"VSS<56>"
$PN"118"16;
"VSS<55>"
$PN"120"16;
"VSS<54>"
$PN"123"16;
"VSS<53>"
$PN"125"16;
"VSS<52>"
$PN"127"16;
"VSS<51>"
$PN"129"16;
"VSS<50>"
$PN"131"16;
"VSS<49>"
$PN"134"16;
"VSS<48>"
$PN"136"16;
"VSS<47>"
$PN"138"16;
"VSS<44>"
$PN"151"17;
"VSS<43>"
$PN"154"17;
"VSS<42>"
$PN"156"17;
"VSS<41>"
$PN"158"17;
"VSS<40>"
$PN"160"17;
"VSS<39>"
$PN"162"17;
"VSS<38>"
$PN"165"17;
"VSS<37>"
$PN"167"17;
"VSS<36>"
$PN"169"17;
"VSS<35>"
$PN"171"17;
"VSS<34>"
$PN"173"17;
"VSS<33>"
$PN"176"17;
"VSS<32>"
$PN"178"17;
"VSS<31>"
$PN"180"17;
"VSS<30>"
$PN"182"17;
"VSS<29>"
$PN"184"17;
"VSS<28>"
$PN"187"17;
"VSS<27>"
$PN"189"17;
"VSS<26>"
$PN"191"17;
"VSS<25>"
$PN"193"17;
"VSS<24>"
$PN"195"17;
"VSS<23>"
$PN"198"17;
"VSS<22>"
$PN"200"17;
"VSS<21>"
$PN"202"17;
"VSS<20>"
$PN"239"17;
"VSS<19>"
$PN"241"17;
"VSS<18>"
$PN"243"17;
"VSS<17>"
$PN"246"17;
"VSS<16>"
$PN"248"17;
"VSS<15>"
$PN"250"17;
"VSS<14>"
$PN"252"17;
"VSS<13>"
$PN"254"17;
"VSS<12>"
$PN"257"17;
"VSS<11>"
$PN"259"17;
"VSS<10>"
$PN"261"17;
"VSS<9>"
$PN"263"17;
"VSS<8>"
$PN"265"17;
"VSS<7>"
$PN"268"17;
"VSS<6>"
$PN"270"17;
"VSS<5>"
$PN"272"17;
"VSS<4>"
$PN"274"17;
"VSS<3>"
$PN"276"17;
"VSS<2>"
$PN"279"17;
"VSS<1>"
$PN"281"17;
"VSS<0>"
$PN"283"17;
"VSS<88>"
$PN"13"16;
"VSS<89>"
$PN"11"16;
"VSS<90>"
$PN"9"16;
"VSS<91>"
$PN"6"16;
"VSS<92>"
$PN"4"16;
"VSS<93>"
$PN"2"16;
%"SCONN288_H44441003"
"1","(-850,2825)","0","mstr_sconn","I14";
;
CDS_SEC"1"
LOCATION"J9M1"
PART_NUMBER"H44441-003"
MATERIAL"SCONN"
BOM_SS"NOPOP"
PACK_TYPE"PIP"
BOM_COST"MEM"
CDS_LIB"mstr_sconn"
SEC_TYPE"PIP"
SEC"1"
CDS_LOCATION"J9M1"
ROOM"DDR4_CH_K";
"DQ<63>"
$PN"280"32;
"BA<1>"
$PN"224"84;
"CK1N"
$PN"219"44;
"CK0P"
$PN"74"99;
"S3_N_C<1>"
$PN"237"67;
"S2_N_C<0>"
$PN"93"68;
"S1_N"
$PN"89"69;
"DQ<29>"
$PN"181"110;
"DQ<28>"
$PN"36"111;
"C<2>"
$PN"235"83;
"A0"
$PN"79"85;
"A1"
$PN"72"86;
"A12"
$PN"65"139;
"A13"
$PN"232"146;
"A17"
$PN"234"140;
"A3"
$PN"71"87;
"A4"
$PN"214"88;
"A5"
$PN"213"89;
"A6"
$PN"69"90;
"A7"
$PN"211"91;
"A8"
$PN"68"92;
"A9"
$PN"66"93;
"CB<6>"
$PN"54"82;
"CB<5>"
$PN"192"70;
"CB<4>"
$PN"47"71;
"CB<3>"
$PN"201"72;
"CB<2>"
$PN"56"73;
"CB<1>"
$PN"194"74;
"CB<0>"
$PN"49"75;
"CK0N"
$PN"75"45;
"CKE<1>"
$PN"203"76;
"DQ<62>"
$PN"135"151;
"DQ<61>"
$PN"273"27;
"DQ<60>"
$PN"128"22;
"DQ<59>"
$PN"282"147;
"DQ<56>"
$PN"130"148;
"DQ<55>"
$PN"269"129;
"DQ<46>"
$PN"113"130;
"DQ<45>"
$PN"251"118;
"DQ<44>"
$PN"106"119;
"DQ<43>"
$PN"260"120;
"DQ<42>"
$PN"115"121;
"DQ<41>"
$PN"253"128;
"DQ<40>"
$PN"108"127;
"DQ<39>"
$PN"247"122;
"DQ<37>"
$PN"240"123;
"DQ<34>"
$PN"104"112;
"DQ<33>"
$PN"242"113;
"DQ<32>"
$PN"97"31;
"DQ<31>"
$PN"188"30;
"DQ<30>"
$PN"43"114;
"DQ<25>"
$PN"183"115;
"DQ<24>"
$PN"38"100;
"DQ<23>"
$PN"177"101;
"DQ<22>"
$PN"32"102;
"DQ<21>"
$PN"170"103;
"DQ<20>"
$PN"25"104;
"DQ<19>"
$PN"179"105;
"DQ<18>"
$PN"34"106;
"DQ<16>"
$PN"27"107;
"DQ<14>"
$PN"21"55;
"DQ<13>"
$PN"159"56;
"DQ<12>"
$PN"14"57;
"DQ<11>"
$PN"168"58;
"DQ<10>"
$PN"23"59;
"DQ<9>"
$PN"161"64;
"DQ<8>"
$PN"16"60;
"DQ<7>"
$PN"155"61;
"DQ<6>"
$PN"10"62;
"EVENT_N"
$PN"78"176;
"PAR"
$PN"222"65;
"RESET_N"
$PN"58"66;
"RFU<2>"
$PN"144"41;
"SCL"
$PN"141"47;
"SDA"
$PN"285"48;
"VREFCA"
$PN"146"40;
"CK1P"
$PN"218"98;
"BG<0>"
$PN"63"97;
"BG<1>"
$PN"207"96;
"BA<0>"
$PN"81"94;
"SA<0>"
$PN"139"20;
"VDDSPD"
$PN"284"20;
"SA<2>"
$PN"238"13;
"SA<1>"
$PN"140"13;
"DQ<1>"
$PN"150"50;
"DQ<0>"
$PN"5"54;
"ACT_N"
$PN"62"49;
"ALERT_N"
$PN"208"29;
"A2"
$PN"216"95;
"DQ<35>"
$PN"249"126;
"DQ<36>"
$PN"95"124;
"DQ<38>"
$PN"102"125;
"A10"
$PN"225"141;
"A11"
$PN"210"142;
"A14_WE_N"
$PN"228"143;
"A15_CAS_N"
$PN"86"144;
"A16_RAS_N"
$PN"82"145;
"CB<7>"
$PN"199"77;
"ODT<0>"
$PN"87"78;
"ODT<1>"
$PN"91"79;
"CKE<0>"
$PN"60"80;
"S0_N"
$PN"84"81;
"DQ<27>"
$PN"190"116;
"DQ<26>"
$PN"45"117;
"DQ<15>"
$PN"166"108;
"DQ<17>"
$PN"172"109;
"RFU<0>"
$PN"205"42;
"RFU<1>"
$PN"227"43;
"SAVE_N_NC"
$PN"230"46;
"DQ<57>"
$PN"275"149;
"DQ<58>"
$PN"137"150;
"DQ<54>"
$PN"124"131;
"DQ<53>"
$PN"262"132;
"DQ<52>"
$PN"117"133;
"DQ<51>"
$PN"271"134;
"DQ<50>"
$PN"126"135;
"DQ<49>"
$PN"264"136;
"DQ<48>"
$PN"119"137;
"DQ<47>"
$PN"258"138;
"DQ<2>"
$PN"12"51;
"DQ<3>"
$PN"157"52;
"DQ<4>"
$PN"3"53;
"DQ<5>"
$PN"148"63;
%"TAP"
"6","(2300,3125)","2","mstr_standard","I142";
;
CDS_LIB"mstr_standard"
BODY_TYPE"PLUMBING"
HDL_TAP"TRUE";
"B \NAC \NWC"2;
"S \NAC"
BN"0"39;
%"TAP"
"6","(2500,3075)","2","mstr_standard","I143";
;
CDS_LIB"mstr_standard"
BODY_TYPE"PLUMBING"
HDL_TAP"TRUE";
"B \NAC \NWC"1;
"S \NAC"
BN"0"153;
%"TAP"
"6","(2500,3175)","2","mstr_standard","I144";
;
CDS_LIB"mstr_standard"
BODY_TYPE"PLUMBING"
HDL_TAP"TRUE";
"B \NAC \NWC"1;
"S \NAC"
BN"1"38;
%"TAP"
"6","(2300,3325)","2","mstr_standard","I145";
;
CDS_LIB"mstr_standard"
BODY_TYPE"PLUMBING"
HDL_TAP"TRUE";
"B \NAC \NWC"2;
"S \NAC"
BN"2"152;
%"TAP"
"6","(2300,3225)","2","mstr_standard","I146";
;
CDS_LIB"mstr_standard"
BODY_TYPE"PLUMBING"
HDL_TAP"TRUE";
"B \NAC \NWC"2;
"S \NAC"
BN"1"37;
%"TAP"
"6","(2300,3425)","2","mstr_standard","I147";
;
CDS_LIB"mstr_standard"
BODY_TYPE"PLUMBING"
HDL_TAP"TRUE";
"B \NAC \NWC"2;
"S \NAC"
BN"3"34;
%"TAP"
"6","(2300,3525)","2","mstr_standard","I148";
;
CDS_LIB"mstr_standard"
BODY_TYPE"PLUMBING"
HDL_TAP"TRUE";
"B \NAC \NWC"2;
"S \NAC"
BN"4"28;
%"TAP"
"6","(2300,3625)","2","mstr_standard","I149";
;
CDS_LIB"mstr_standard"
BODY_TYPE"PLUMBING"
HDL_TAP"TRUE";
"B \NAC \NWC"2;
"S \NAC"
BN"5"155;
%"TAP"
"6","(2500,3275)","2","mstr_standard","I150";
;
CDS_LIB"mstr_standard"
BODY_TYPE"PLUMBING"
HDL_TAP"TRUE";
"B \NAC \NWC"1;
"S \NAC"
BN"2"36;
%"TAP"
"6","(2500,3375)","2","mstr_standard","I151";
;
CDS_LIB"mstr_standard"
BODY_TYPE"PLUMBING"
HDL_TAP"TRUE";
"B \NAC \NWC"1;
"S \NAC"
BN"3"35;
%"TAP"
"6","(2500,3675)","2","mstr_standard","I152";
;
CDS_LIB"mstr_standard"
BODY_TYPE"PLUMBING"
HDL_TAP"TRUE";
"B \NAC \NWC"1;
"S \NAC"
BN"6"24;
%"TAP"
"6","(2500,3575)","2","mstr_standard","I153";
;
CDS_LIB"mstr_standard"
BODY_TYPE"PLUMBING"
HDL_TAP"TRUE";
"B \NAC \NWC"1;
"S \NAC"
BN"5"154;
%"TAP"
"6","(2500,3475)","2","mstr_standard","I154";
;
CDS_LIB"mstr_standard"
BODY_TYPE"PLUMBING"
HDL_TAP"TRUE";
"B \NAC \NWC"1;
"S \NAC"
BN"4"33;
%"GND"
"1","(4100,725)","2","mstr_symbols","I155";
;
VOLTAGE"0"
CDS_LIB"mstr_symbols"
SIZE"1B"
BOM_COST"MEM"
BODY_TYPE"PLUMBING"
ROOM"DDR4_CH_C"
HDL_POWER"GND";
"A\NAC"17;
%"TAP"
"6","(2300,3725)","2","mstr_standard","I156";
;
CDS_LIB"mstr_standard"
BODY_TYPE"PLUMBING"
HDL_TAP"TRUE";
"B \NAC \NWC"2;
"S \NAC"
BN"6"156;
%"TAP"
"6","(2300,3825)","2","mstr_standard","I157";
;
CDS_LIB"mstr_standard"
BODY_TYPE"PLUMBING"
HDL_TAP"TRUE";
"B \NAC \NWC"2;
"S \NAC"
BN"7"25;
%"TAP"
"6","(2300,3925)","2","mstr_standard","I158";
;
CDS_LIB"mstr_standard"
BODY_TYPE"PLUMBING"
HDL_TAP"TRUE";
"B \NAC \NWC"2;
"S \NAC"
BN"8"157;
%"TAP"
"6","(2300,4025)","2","mstr_standard","I159";
;
CDS_LIB"mstr_standard"
BODY_TYPE"PLUMBING"
HDL_TAP"TRUE";
"B \NAC \NWC"2;
"S \NAC"
BN"9"158;
%"TAP"
"6","(2300,4225)","2","mstr_standard","I160";
;
CDS_LIB"mstr_standard"
BODY_TYPE"PLUMBING"
HDL_TAP"TRUE";
"B \NAC \NWC"2;
"S \NAC"
BN"11"163;
%"TAP"
"6","(2300,4125)","2","mstr_standard","I161";
;
CDS_LIB"mstr_standard"
BODY_TYPE"PLUMBING"
HDL_TAP"TRUE";
"B \NAC \NWC"2;
"S \NAC"
BN"10"162;
%"TAP"
"6","(2500,3975)","2","mstr_standard","I162";
;
CDS_LIB"mstr_standard"
BODY_TYPE"PLUMBING"
HDL_TAP"TRUE";
"B \NAC \NWC"1;
"S \NAC"
BN"9"161;
%"TAP"
"6","(2500,3775)","2","mstr_standard","I163";
;
CDS_LIB"mstr_standard"
BODY_TYPE"PLUMBING"
HDL_TAP"TRUE";
"B \NAC \NWC"1;
"S \NAC"
BN"7"23;
%"TAP"
"6","(2500,3875)","2","mstr_standard","I164";
;
CDS_LIB"mstr_standard"
BODY_TYPE"PLUMBING"
HDL_TAP"TRUE";
"B \NAC \NWC"1;
"S \NAC"
BN"8"160;
%"TAP"
"6","(2500,4175)","2","mstr_standard","I165";
;
CDS_LIB"mstr_standard"
BODY_TYPE"PLUMBING"
HDL_TAP"TRUE";
"B \NAC \NWC"1;
"S \NAC"
BN"11"167;
%"TAP"
"6","(2500,4075)","2","mstr_standard","I166";
;
CDS_LIB"mstr_standard"
BODY_TYPE"PLUMBING"
HDL_TAP"TRUE";
"B \NAC \NWC"1;
"S \NAC"
BN"10"159;
%"TAP"
"6","(2300,4325)","2","mstr_standard","I167";
;
CDS_LIB"mstr_standard"
BODY_TYPE"PLUMBING"
HDL_TAP"TRUE";
"B \NAC \NWC"2;
"S \NAC"
BN"12"164;
%"TAP"
"6","(2300,4425)","2","mstr_standard","I168";
;
CDS_LIB"mstr_standard"
BODY_TYPE"PLUMBING"
HDL_TAP"TRUE";
"B \NAC \NWC"2;
"S \NAC"
BN"13"165;
%"TAP"
"6","(2300,4525)","2","mstr_standard","I169";
;
CDS_LIB"mstr_standard"
BODY_TYPE"PLUMBING"
HDL_TAP"TRUE";
"B \NAC \NWC"2;
"S \NAC"
BN"14"166;
%"TAP"
"6","(2300,4625)","2","mstr_standard","I170";
;
CDS_LIB"mstr_standard"
BODY_TYPE"PLUMBING"
HDL_TAP"TRUE";
"B \NAC \NWC"2;
"S \NAC"
BN"15"171;
%"TAP"
"6","(2300,4725)","2","mstr_standard","I171";
;
CDS_LIB"mstr_standard"
BODY_TYPE"PLUMBING"
HDL_TAP"TRUE";
"B \NAC \NWC"2;
"S \NAC"
BN"16"172;
%"TAP"
"6","(2500,4475)","2","mstr_standard","I172";
;
CDS_LIB"mstr_standard"
BODY_TYPE"PLUMBING"
HDL_TAP"TRUE";
"B \NAC \NWC"1;
"S \NAC"
BN"14"170;
%"TAP"
"6","(2500,4275)","2","mstr_standard","I173";
;
CDS_LIB"mstr_standard"
BODY_TYPE"PLUMBING"
HDL_TAP"TRUE";
"B \NAC \NWC"1;
"S \NAC"
BN"12"168;
%"TAP"
"6","(2500,4375)","2","mstr_standard","I174";
;
CDS_LIB"mstr_standard"
BODY_TYPE"PLUMBING"
HDL_TAP"TRUE";
"B \NAC \NWC"1;
"S \NAC"
BN"13"169;
%"TAP"
"6","(2500,4675)","2","mstr_standard","I175";
;
CDS_LIB"mstr_standard"
BODY_TYPE"PLUMBING"
HDL_TAP"TRUE";
"B \NAC \NWC"1;
"S \NAC"
BN"16"174;
%"TAP"
"6","(2500,4575)","2","mstr_standard","I176";
;
CDS_LIB"mstr_standard"
BODY_TYPE"PLUMBING"
HDL_TAP"TRUE";
"B \NAC \NWC"1;
"S \NAC"
BN"15"26;
%"TAP"
"6","(2300,4825)","2","mstr_standard","I177";
;
CDS_LIB"mstr_standard"
BODY_TYPE"PLUMBING"
HDL_TAP"TRUE";
"B \NAC \NWC"2;
"S \NAC"
BN"17"173;
%"TAP"
"6","(2500,4775)","2","mstr_standard","I178";
;
CDS_LIB"mstr_standard"
BODY_TYPE"PLUMBING"
HDL_TAP"TRUE";
"B \NAC \NWC"1;
"S \NAC"
BN"17"175;
%"P12V_NVDIMM_KLM"
"1","(2150,2800)","0","mstr_symbols","I181";
;
VOLTAGE"12.0"
CDS_LIB"mstr_symbols"
BODY_TYPE"PLUMBING"
HDL_POWER"P12V_NVDIMM_KLM";
"G\NAC"18;
%"TAP"
"6","(-1600,2125)","0","mstr_standard","I19";
;
CDS_LIB"mstr_standard"
BODY_TYPE"PLUMBING"
HDL_TAP"TRUE";
"B \NAC \NWC"8;
"S \NAC"
BN"1"74;
%"TAP"
"6","(-1600,2075)","0","mstr_standard","I20";
;
CDS_LIB"mstr_standard"
BODY_TYPE"PLUMBING"
HDL_TAP"TRUE";
"B \NAC \NWC"8;
"S \NAC"
BN"0"75;
%"TAP"
"6","(-1600,2175)","0","mstr_standard","I21";
;
CDS_LIB"mstr_standard"
BODY_TYPE"PLUMBING"
HDL_TAP"TRUE";
"B \NAC \NWC"8;
"S \NAC"
BN"2"73;
%"TAP"
"6","(-1600,2225)","0","mstr_standard","I22";
;
CDS_LIB"mstr_standard"
BODY_TYPE"PLUMBING"
HDL_TAP"TRUE";
"B \NAC \NWC"8;
"S \NAC"
BN"3"72;
%"TAP"
"6","(-1600,2275)","0","mstr_standard","I23";
;
CDS_LIB"mstr_standard"
BODY_TYPE"PLUMBING"
HDL_TAP"TRUE";
"B \NAC \NWC"8;
"S \NAC"
BN"4"71;
%"TAP"
"6","(-1600,2375)","0","mstr_standard","I24";
;
CDS_LIB"mstr_standard"
BODY_TYPE"PLUMBING"
HDL_TAP"TRUE";
"B \NAC \NWC"8;
"S \NAC"
BN"6"82;
%"TAP"
"6","(-1600,2325)","0","mstr_standard","I25";
;
CDS_LIB"mstr_standard"
BODY_TYPE"PLUMBING"
HDL_TAP"TRUE";
"B \NAC \NWC"8;
"S \NAC"
BN"5"70;
%"TAP"
"6","(-1600,2425)","0","mstr_standard","I26";
;
CDS_LIB"mstr_standard"
BODY_TYPE"PLUMBING"
HDL_TAP"TRUE";
"B \NAC \NWC"8;
"S \NAC"
BN"7"77;
%"TAP"
"6","(-1600,2525)","0","mstr_standard","I27";
;
CDS_LIB"mstr_standard"
BODY_TYPE"PLUMBING"
HDL_TAP"TRUE";
"B \NAC \NWC"11;
"S \NAC"
BN"2"78;
%"TAP"
"6","(-1600,2575)","0","mstr_standard","I28";
;
CDS_LIB"mstr_standard"
BODY_TYPE"PLUMBING"
HDL_TAP"TRUE";
"B \NAC \NWC"11;
"S \NAC"
BN"3"79;
%"TAP"
"6","(-1600,2675)","0","mstr_standard","I29";
;
CDS_LIB"mstr_standard"
BODY_TYPE"PLUMBING"
HDL_TAP"TRUE";
"B \NAC \NWC"10;
"S \NAC"
BN"2"80;
%"GND"
"1","(-3000,875)","0","mstr_symbols","I3";
;
VOLTAGE"0"
CDS_LIB"mstr_symbols"
SIZE"1B"
BOM_COST"MEM"
BODY_TYPE"PLUMBING"
ROOM"DDR4_CH_C"
HDL_POWER"GND";
"A\NAC"19;
%"TAP"
"6","(-2100,3125)","0","mstr_standard","I33";
;
CDS_LIB"mstr_standard"
BODY_TYPE"PLUMBING"
HDL_TAP"TRUE";
"B \NAC \NWC"12;
"S \NAC"
BN"2"45;
%"TAP"
"6","(-1950,3175)","0","mstr_standard","I34";
;
CDS_LIB"mstr_standard"
BODY_TYPE"PLUMBING"
HDL_TAP"TRUE";
"B \NAC \NWC"5;
"S \NAC"
BN"2"99;
%"TAP"
"6","(-2100,3225)","0","mstr_standard","I37";
;
CDS_LIB"mstr_standard"
BODY_TYPE"PLUMBING"
HDL_TAP"TRUE";
"B \NAC \NWC"12;
"S \NAC"
BN"3"44;
%"TAP"
"6","(-1950,3275)","0","mstr_standard","I38";
;
CDS_LIB"mstr_standard"
BODY_TYPE"PLUMBING"
HDL_TAP"TRUE";
"B \NAC \NWC"5;
"S \NAC"
BN"3"98;
%"TAP"
"6","(-1600,2725)","0","mstr_standard","I39";
;
CDS_LIB"mstr_standard"
BODY_TYPE"PLUMBING"
HDL_TAP"TRUE";
"B \NAC \NWC"10;
"S \NAC"
BN"3"76;
%"CAP_A"
"1","(-3000,1125)","2","dev_discrete","I4";
;
LOCATION"C9M1"
PART_NUMBER"A36096-045"
VALUE"0.01UF"
TOLERANCE"10%"
PACK_TYPE"0402V"
VOLTAGE"25V"
MATERIAL"X7R"
CDS_LOCATION"C9M1"
BOM_COST"MEM"
CDS_LIB"dev_discrete"
CDS_SEC"1"
$SEC"1"
ROOM"DDR4_CH_C";
"B"
$PN"2"19;
"A"
$PN"1"40;
%"TAP"
"6","(-1600,2925)","0","mstr_standard","I40";
;
CDS_LIB"mstr_standard"
BODY_TYPE"PLUMBING"
HDL_TAP"TRUE";
"B \NAC \NWC"9;
"S \NAC"
BN"6"68;
%"TAP"
"6","(-1600,2875)","0","mstr_standard","I41";
;
CDS_LIB"mstr_standard"
BODY_TYPE"PLUMBING"
HDL_TAP"TRUE";
"B \NAC \NWC"9;
"S \NAC"
BN"5"69;
%"TAP"
"6","(-1600,2825)","0","mstr_standard","I42";
;
CDS_LIB"mstr_standard"
BODY_TYPE"PLUMBING"
HDL_TAP"TRUE";
"B \NAC \NWC"9;
"S \NAC"
BN"4"81;
%"TAP"
"6","(-1600,2975)","0","mstr_standard","I43";
;
CDS_LIB"mstr_standard"
BODY_TYPE"PLUMBING"
HDL_TAP"TRUE";
"B \NAC \NWC"9;
"S \NAC"
BN"7"67;
%"TAP"
"6","(-1600,3425)","0","mstr_standard","I44";
;
CDS_LIB"mstr_standard"
BODY_TYPE"PLUMBING"
HDL_TAP"TRUE";
"B \NAC \NWC"6;
"S \NAC"
BN"1"96;
%"TAP"
"6","(-1600,3375)","0","mstr_standard","I45";
;
CDS_LIB"mstr_standard"
BODY_TYPE"PLUMBING"
HDL_TAP"TRUE";
"B \NAC \NWC"6;
"S \NAC"
BN"0"97;
%"TAP"
"6","(-1600,3675)","0","mstr_standard","I46";
;
CDS_LIB"mstr_standard"
BODY_TYPE"PLUMBING"
HDL_TAP"TRUE";
"B \NAC \NWC"4;
"S \NAC"
BN"1"86;
%"TAP"
"6","(-1600,3625)","0","mstr_standard","I47";
;
CDS_LIB"mstr_standard"
BODY_TYPE"PLUMBING"
HDL_TAP"TRUE";
"B \NAC \NWC"4;
"S \NAC"
BN"0"85;
%"TAP"
"6","(-1600,3475)","0","mstr_standard","I48";
;
CDS_LIB"mstr_standard"
BODY_TYPE"PLUMBING"
HDL_TAP"TRUE";
"B \NAC \NWC"7;
"S \NAC"
BN"0"94;
%"TAP"
"6","(-1600,3525)","0","mstr_standard","I49";
;
CDS_LIB"mstr_standard"
BODY_TYPE"PLUMBING"
HDL_TAP"TRUE";
"B \NAC \NWC"7;
"S \NAC"
BN"1"84;
%"PVPP_KLM"
"1","(-3500,1825)","0","mstr_symbols","I5";
;
VOLTAGE"2.5V"
BOM_COST"MEM"
CDS_LIB"mstr_symbols"
BODY_TYPE"PLUMBING"
ROOM"DDR4_CH_C"
HDL_POWER"PVPP_KLM";
"G\NAC"20;
%"TAP"
"6","(-100,1325)","2","mstr_standard","I50";
;
CDS_LIB"mstr_standard"
BODY_TYPE"PLUMBING"
HDL_TAP"TRUE";
"B \NAC \NWC"3;
"S \NAC"
BN"0"54;
%"TAP"
"6","(-100,1375)","2","mstr_standard","I51";
;
CDS_LIB"mstr_standard"
BODY_TYPE"PLUMBING"
HDL_TAP"TRUE";
"B \NAC \NWC"3;
"S \NAC"
BN"1"50;
%"TAP"
"6","(-100,1425)","2","mstr_standard","I52";
;
CDS_LIB"mstr_standard"
BODY_TYPE"PLUMBING"
HDL_TAP"TRUE";
"B \NAC \NWC"3;
"S \NAC"
BN"2"51;
%"TAP"
"6","(-100,1475)","2","mstr_standard","I53";
;
CDS_LIB"mstr_standard"
BODY_TYPE"PLUMBING"
HDL_TAP"TRUE";
"B \NAC \NWC"3;
"S \NAC"
BN"3"52;
%"TAP"
"6","(-100,1525)","2","mstr_standard","I54";
;
CDS_LIB"mstr_standard"
BODY_TYPE"PLUMBING"
HDL_TAP"TRUE";
"B \NAC \NWC"3;
"S \NAC"
BN"4"53;
%"TAP"
"6","(-100,1625)","2","mstr_standard","I55";
;
CDS_LIB"mstr_standard"
BODY_TYPE"PLUMBING"
HDL_TAP"TRUE";
"B \NAC \NWC"3;
"S \NAC"
BN"6"62;
%"TAP"
"6","(-100,1575)","2","mstr_standard","I56";
;
CDS_LIB"mstr_standard"
BODY_TYPE"PLUMBING"
HDL_TAP"TRUE";
"B \NAC \NWC"3;
"S \NAC"
BN"5"63;
%"SCONN288_H44441003"
"4","(1450,1725)","0","mstr_sconn","I57";
;
CDS_SEC"4"
PART_NUMBER"H44441-003"
MATERIAL"SCONN"
LOCATION"J9M1"
BOM_SS"NOPOP"
PACK_TYPE"PIP"
BOM_COST"MEM"
CDS_LIB"mstr_sconn"
SEC_TYPE"PIP"
SEC"4"
CDS_LOCATION"J9M1"
ROOM"DDR4_CH_K";
"VDD<0>"
$PN"236"21;
"VDD<6>"
$PN"220"21;
"VDD<10>"
$PN"209"21;
"VDD<13>"
$PN"92"21;
"VDD<16>"
$PN"85"21;
"VDD<19>"
$PN"76"21;
"VDD<23>"
$PN"64"21;
"VDD<25>"
$PN"59"21;
"VTT<0>"
$PN"221"14;
"12V<1>"
$PN"1"18;
"12V<0>"
$PN"145"18;
"VDD<24>"
$PN"61"21;
"VDD<22>"
$PN"67"21;
"VDD<21>"
$PN"70"21;
"VDD<20>"
$PN"73"21;
"VDD<18>"
$PN"80"21;
"VDD<17>"
$PN"83"21;
"VDD<15>"
$PN"88"21;
"VDD<14>"
$PN"90"21;
"VDD<12>"
$PN"204"21;
"VDD<11>"
$PN"206"21;
"VDD<9>"
$PN"212"21;
"VDD<8>"
$PN"215"21;
"VDD<7>"
$PN"217"21;
"VDD<5>"
$PN"223"21;
"VDD<4>"
$PN"226"21;
"VDD<3>"
$PN"229"21;
"VDD<2>"
$PN"231"21;
"VDD<1>"
$PN"233"21;
"VPP<4>"
$PN"142"15;
"VPP<3>"
$PN"143"15;
"VPP<2>"
$PN"288"15;
"VPP<1>"
$PN"286"15;
"VPP<0>"
$PN"287"15;
"VTT<1>"
$PN"77"14;
%"TAP"
"6","(-100,1775)","2","mstr_standard","I58";
;
CDS_LIB"mstr_standard"
BODY_TYPE"PLUMBING"
HDL_TAP"TRUE";
"B \NAC \NWC"3;
"S \NAC"
BN"9"64;
%"TAP"
"6","(-100,1675)","2","mstr_standard","I59";
;
CDS_LIB"mstr_standard"
BODY_TYPE"PLUMBING"
HDL_TAP"TRUE";
"B \NAC \NWC"3;
"S \NAC"
BN"7"61;
%"TAP"
"6","(-100,1725)","2","mstr_standard","I60";
;
CDS_LIB"mstr_standard"
BODY_TYPE"PLUMBING"
HDL_TAP"TRUE";
"B \NAC \NWC"3;
"S \NAC"
BN"8"60;
%"TAP"
"6","(-100,1875)","2","mstr_standard","I61";
;
CDS_LIB"mstr_standard"
BODY_TYPE"PLUMBING"
HDL_TAP"TRUE";
"B \NAC \NWC"3;
"S \NAC"
BN"11"58;
%"TAP"
"6","(-100,1925)","2","mstr_standard","I62";
;
CDS_LIB"mstr_standard"
BODY_TYPE"PLUMBING"
HDL_TAP"TRUE";
"B \NAC \NWC"3;
"S \NAC"
BN"12"57;
%"TAP"
"6","(-100,1825)","2","mstr_standard","I63";
;
CDS_LIB"mstr_standard"
BODY_TYPE"PLUMBING"
HDL_TAP"TRUE";
"B \NAC \NWC"3;
"S \NAC"
BN"10"59;
%"TAP"
"6","(-100,2025)","2","mstr_standard","I64";
;
CDS_LIB"mstr_standard"
BODY_TYPE"PLUMBING"
HDL_TAP"TRUE";
"B \NAC \NWC"3;
"S \NAC"
BN"14"55;
%"TAP"
"6","(-100,1975)","2","mstr_standard","I65";
;
CDS_LIB"mstr_standard"
BODY_TYPE"PLUMBING"
HDL_TAP"TRUE";
"B \NAC \NWC"3;
"S \NAC"
BN"13"56;
%"TAP"
"6","(-100,2125)","2","mstr_standard","I66";
;
CDS_LIB"mstr_standard"
BODY_TYPE"PLUMBING"
HDL_TAP"TRUE";
"B \NAC \NWC"3;
"S \NAC"
BN"16"107;
%"TAP"
"6","(-100,2175)","2","mstr_standard","I67";
;
CDS_LIB"mstr_standard"
BODY_TYPE"PLUMBING"
HDL_TAP"TRUE";
"B \NAC \NWC"3;
"S \NAC"
BN"17"109;
%"TAP"
"6","(-100,2075)","2","mstr_standard","I68";
;
CDS_LIB"mstr_standard"
BODY_TYPE"PLUMBING"
HDL_TAP"TRUE";
"B \NAC \NWC"3;
"S \NAC"
BN"15"108;
%"TAP"
"6","(-100,2275)","2","mstr_standard","I69";
;
CDS_LIB"mstr_standard"
BODY_TYPE"PLUMBING"
HDL_TAP"TRUE";
"B \NAC \NWC"3;
"S \NAC"
BN"19"105;
%"TAP"
"6","(-100,2225)","2","mstr_standard","I70";
;
CDS_LIB"mstr_standard"
BODY_TYPE"PLUMBING"
HDL_TAP"TRUE";
"B \NAC \NWC"3;
"S \NAC"
BN"18"106;
%"TAP"
"6","(-100,2425)","2","mstr_standard","I71";
;
CDS_LIB"mstr_standard"
BODY_TYPE"PLUMBING"
HDL_TAP"TRUE";
"B \NAC \NWC"3;
"S \NAC"
BN"22"102;
%"TAP"
"6","(-100,2375)","2","mstr_standard","I72";
;
CDS_LIB"mstr_standard"
BODY_TYPE"PLUMBING"
HDL_TAP"TRUE";
"B \NAC \NWC"3;
"S \NAC"
BN"21"103;
%"TAP"
"6","(-100,2325)","2","mstr_standard","I73";
;
CDS_LIB"mstr_standard"
BODY_TYPE"PLUMBING"
HDL_TAP"TRUE";
"B \NAC \NWC"3;
"S \NAC"
BN"20"104;
%"TAP"
"6","(-100,2475)","2","mstr_standard","I74";
;
CDS_LIB"mstr_standard"
BODY_TYPE"PLUMBING"
HDL_TAP"TRUE";
"B \NAC \NWC"3;
"S \NAC"
BN"23"101;
%"TAP"
"6","(-100,2525)","2","mstr_standard","I75";
;
CDS_LIB"mstr_standard"
BODY_TYPE"PLUMBING"
HDL_TAP"TRUE";
"B \NAC \NWC"3;
"S \NAC"
BN"24"100;
%"TAP"
"6","(-100,2675)","2","mstr_standard","I76";
;
CDS_LIB"mstr_standard"
BODY_TYPE"PLUMBING"
HDL_TAP"TRUE";
"B \NAC \NWC"3;
"S \NAC"
BN"27"116;
%"TAP"
"6","(-100,2625)","2","mstr_standard","I77";
;
CDS_LIB"mstr_standard"
BODY_TYPE"PLUMBING"
HDL_TAP"TRUE";
"B \NAC \NWC"3;
"S \NAC"
BN"26"117;
%"TAP"
"6","(-100,2575)","2","mstr_standard","I78";
;
CDS_LIB"mstr_standard"
BODY_TYPE"PLUMBING"
HDL_TAP"TRUE";
"B \NAC \NWC"3;
"S \NAC"
BN"25"115;
%"PVDDQ_KLM"
"1","(325,2275)","0","mstr_symbols","I79";
;
VOLTAGE"1.2V"
BOM_COST"MEM"
CDS_LIB"mstr_symbols"
BODY_TYPE"PLUMBING"
ROOM"DDR4_CH_C"
HDL_POWER"PVDDQ_KLM";
"G\NAC"21;
%"TAP"
"6","(-100,2725)","2","mstr_standard","I80";
;
CDS_LIB"mstr_standard"
BODY_TYPE"PLUMBING"
HDL_TAP"TRUE";
"B \NAC \NWC"3;
"S \NAC"
BN"28"111;
%"TAP"
"6","(-100,2775)","2","mstr_standard","I81";
;
CDS_LIB"mstr_standard"
BODY_TYPE"PLUMBING"
HDL_TAP"TRUE";
"B \NAC \NWC"3;
"S \NAC"
BN"29"110;
%"TAP"
"6","(-100,2825)","2","mstr_standard","I82";
;
CDS_LIB"mstr_standard"
BODY_TYPE"PLUMBING"
HDL_TAP"TRUE";
"B \NAC \NWC"3;
"S \NAC"
BN"30"114;
%"TAP"
"6","(-100,2875)","2","mstr_standard","I83";
;
CDS_LIB"mstr_standard"
BODY_TYPE"PLUMBING"
HDL_TAP"TRUE";
"B \NAC \NWC"3;
"S \NAC"
BN"31"30;
%"TAP"
"6","(-100,2925)","2","mstr_standard","I84";
;
CDS_LIB"mstr_standard"
BODY_TYPE"PLUMBING"
HDL_TAP"TRUE";
"B \NAC \NWC"3;
"S \NAC"
BN"32"31;
%"TAP"
"6","(-100,2975)","2","mstr_standard","I85";
;
CDS_LIB"mstr_standard"
BODY_TYPE"PLUMBING"
HDL_TAP"TRUE";
"B \NAC \NWC"3;
"S \NAC"
BN"33"113;
%"TAP"
"6","(-100,3025)","2","mstr_standard","I86";
;
CDS_LIB"mstr_standard"
BODY_TYPE"PLUMBING"
HDL_TAP"TRUE";
"B \NAC \NWC"3;
"S \NAC"
BN"34"112;
%"TAP"
"6","(-100,3075)","2","mstr_standard","I87";
;
CDS_LIB"mstr_standard"
BODY_TYPE"PLUMBING"
HDL_TAP"TRUE";
"B \NAC \NWC"3;
"S \NAC"
BN"35"126;
%"TAP"
"6","(-100,3125)","2","mstr_standard","I88";
;
CDS_LIB"mstr_standard"
BODY_TYPE"PLUMBING"
HDL_TAP"TRUE";
"B \NAC \NWC"3;
"S \NAC"
BN"36"124;
%"TAP"
"6","(-100,3175)","2","mstr_standard","I89";
;
CDS_LIB"mstr_standard"
BODY_TYPE"PLUMBING"
HDL_TAP"TRUE";
"B \NAC \NWC"3;
"S \NAC"
BN"37"123;
%"TAP"
"6","(-100,3225)","2","mstr_standard","I90";
;
CDS_LIB"mstr_standard"
BODY_TYPE"PLUMBING"
HDL_TAP"TRUE";
"B \NAC \NWC"3;
"S \NAC"
BN"38"125;
%"TAP"
"6","(-100,3325)","2","mstr_standard","I91";
;
CDS_LIB"mstr_standard"
BODY_TYPE"PLUMBING"
HDL_TAP"TRUE";
"B \NAC \NWC"3;
"S \NAC"
BN"40"127;
%"TAP"
"6","(-100,3275)","2","mstr_standard","I92";
;
CDS_LIB"mstr_standard"
BODY_TYPE"PLUMBING"
HDL_TAP"TRUE";
"B \NAC \NWC"3;
"S \NAC"
BN"39"122;
%"TAP"
"6","(-100,3425)","2","mstr_standard","I93";
;
CDS_LIB"mstr_standard"
BODY_TYPE"PLUMBING"
HDL_TAP"TRUE";
"B \NAC \NWC"3;
"S \NAC"
BN"42"121;
%"TAP"
"6","(-100,3375)","2","mstr_standard","I94";
;
CDS_LIB"mstr_standard"
BODY_TYPE"PLUMBING"
HDL_TAP"TRUE";
"B \NAC \NWC"3;
"S \NAC"
BN"41"128;
%"TAP"
"6","(-100,3475)","2","mstr_standard","I95";
;
CDS_LIB"mstr_standard"
BODY_TYPE"PLUMBING"
HDL_TAP"TRUE";
"B \NAC \NWC"3;
"S \NAC"
BN"43"120;
%"TAP"
"6","(-100,3575)","2","mstr_standard","I96";
;
CDS_LIB"mstr_standard"
BODY_TYPE"PLUMBING"
HDL_TAP"TRUE";
"B \NAC \NWC"3;
"S \NAC"
BN"45"118;
%"TAP"
"6","(-100,3525)","2","mstr_standard","I97";
;
CDS_LIB"mstr_standard"
BODY_TYPE"PLUMBING"
HDL_TAP"TRUE";
"B \NAC \NWC"3;
"S \NAC"
BN"44"119;
%"TAP"
"6","(-100,3675)","2","mstr_standard","I98";
;
CDS_LIB"mstr_standard"
BODY_TYPE"PLUMBING"
HDL_TAP"TRUE";
"B \NAC \NWC"3;
"S \NAC"
BN"47"138;
%"TAP"
"6","(-100,3625)","2","mstr_standard","I99";
;
CDS_LIB"mstr_standard"
BODY_TYPE"PLUMBING"
HDL_TAP"TRUE";
"B \NAC \NWC"3;
"S \NAC"
BN"46"130;
END.
